# SCM (Grand Teton) — schematic netlist excerpt (pin names and nets, part order shuffled) for the footprints in the layout excerpt that follows; sources: Cadence DE-HDL packaged netlist, KiCad conversion of 12092022_DA0F0TMDCD0_F0T_Management_Board_D_brd_V3_OCP.brd

C337  Q_CAP  0.1UF 25V 10% X7R  pkg 0402  page 22 : A = P3V3_AUX ; B = GND
R804  Q_RES  0 5% CHIP  pkg 0402LF  page 15 : A = SYS_BMC_PWRBTN_R1_N ; B = SYS_BMC_PWRBTN_R_N

(kicad_pcb
	(version 20260206)
	(generator "pcbnew")
	(generator_version "10.0")
	(general
		(thickness 1.6)
		(legacy_teardrops no)
	)
	(paper "A4")
	(title_block
		(title "12092022_DA0F0TMDCD0_F0T_Management_Board_D_brd_V3_OCP.brd")
		(comment 1 "Grand Teton / footprints 1207-1208 of 1440")
	)
	(layers
		(0 "F.Cu" signal "TOP")
		(4 "In1.Cu" signal "GND")
		(6 "In2.Cu" signal "IN1")
		(8 "In3.Cu" signal "GND1")
		(10 "In4.Cu" signal "IN2")
		(12 "In5.Cu" signal "VCC")
		(14 "In6.Cu" signal "VCC1")
		(16 "In7.Cu" signal "IN3")
		(18 "In8.Cu" signal "GND2")
		(20 "In9.Cu" signal "IN4")
		(22 "In10.Cu" signal "GND3")
		(2 "B.Cu" signal "BOTTOM")
		(9 "F.Adhes" user "F.Adhesive")
		(11 "B.Adhes" user "B.Adhesive")
		(13 "F.Paste" user "Package Geometry/Pastemask Top")
		(15 "B.Paste" user "Package Geometry/Pastemask Bottom")
		(5 "F.SilkS" user "Ref Des/Silkscreen Top")
		(7 "B.SilkS" user "Ref Des/Silkscreen Bottom")
		(1 "F.Mask" user "Board Geometry/Soldermask Top")
		(3 "B.Mask" user "Board Geometry/Soldermask Bottom")
		(17 "Dwgs.User" user "User.Drawings")
		(19 "Cmts.User" user "User.Comments")
		(21 "Eco1.User" user "User.Eco1")
		(23 "Eco2.User" user "User.Eco2")
		(25 "Edge.Cuts" user "Board Geometry/Outline")
		(27 "Margin" user)
		(31 "F.CrtYd" user "Package Geometry/Place Bound Top")
		(29 "B.CrtYd" user "Package Geometry/Place Bound Bottom")
		(35 "F.Fab" user "Ref Des/Assembly Top")
		(33 "B.Fab" user "Ref Des/Assembly Bottom")
	)
	(footprint ""
		(layer "B.Cu")
		(at 30.3784 -95.7072)
		(property "Reference" "C337"
			(at 0 0 0)
			(layer "B.SilkS")
			(hide yes)
			(effects
				(font
					(size 1.27 1.27)
				)
				(justify mirror)
			)
		)
		(property "Value" ""
			(at 0 0 0)
			(layer "B.Fab")
			(effects
				(font
					(size 1.27 1.27)
				)
				(justify mirror)
			)
		)
		(duplicate_pad_numbers_are_jumpers no)
		(fp_line
			(start -0.7874 -0.4064)
			(end -0.7874 0.4064)
			(stroke
				(width 0.1524)
				(type default)
			)
			(layer "B.SilkS")
		)
		(fp_line
			(start -0.7874 0.4064)
			(end 0.7874 0.4064)
			(stroke
				(width 0.1524)
				(type default)
			)
			(layer "B.SilkS")
		)
		(fp_line
			(start 0.7874 -0.4064)
			(end -0.7874 -0.4064)
			(stroke
				(width 0.1524)
				(type default)
			)
			(layer "B.SilkS")
		)
		(fp_line
			(start 0.7874 0.4064)
			(end 0.7874 -0.4064)
			(stroke
				(width 0.1524)
				(type default)
			)
			(layer "B.SilkS")
		)
		(fp_line
			(start -0.67945 -0.3048)
			(end -0.67945 0.3048)
			(stroke
				(width 0.1)
				(type default)
			)
			(layer "B.Fab")
		)
		(fp_line
			(start -0.67945 0.3048)
			(end -0.120396 0.3048)
			(stroke
				(width 0.1)
				(type default)
			)
			(layer "B.Fab")
		)
		(fp_line
			(start -0.12065 -0.3048)
			(end -0.67945 -0.3048)
			(stroke
				(width 0.1)
				(type default)
			)
			(layer "B.Fab")
		)
		(fp_line
			(start -0.12065 -0.2794)
			(end -0.12065 -0.3048)
			(stroke
				(width 0.1)
				(type default)
			)
			(layer "B.Fab")
		)
		(fp_line
			(start -0.120396 0.2794)
			(end 0.12065 0.2794)
			(stroke
				(width 0.1)
				(type default)
			)
			(layer "B.Fab")
		)
		(fp_line
			(start -0.120396 0.3048)
			(end -0.120396 0.2794)
			(stroke
				(width 0.1)
				(type default)
			)
			(layer "B.Fab")
		)
		(fp_line
			(start 0.12065 -0.305054)
			(end 0.12065 -0.2794)
			(stroke
				(width 0.1)
				(type default)
			)
			(layer "B.Fab")
		)
		(fp_line
			(start 0.12065 -0.2794)
			(end -0.12065 -0.2794)
			(stroke
				(width 0.1)
				(type default)
			)
			(layer "B.Fab")
		)
		(fp_line
			(start 0.12065 0.2794)
			(end 0.12065 0.3048)
			(stroke
				(width 0.1)
				(type default)
			)
			(layer "B.Fab")
		)
		(fp_line
			(start 0.12065 0.3048)
			(end 0.67945 0.3048)
			(stroke
				(width 0.1)
				(type default)
			)
			(layer "B.Fab")
		)
		(fp_line
			(start 0.67945 -0.305054)
			(end 0.12065 -0.305054)
			(stroke
				(width 0.1)
				(type default)
			)
			(layer "B.Fab")
		)
		(fp_line
			(start 0.67945 0.3048)
			(end 0.67945 -0.305054)
			(stroke
				(width 0.1)
				(type default)
			)
			(layer "B.Fab")
		)
		(pad "1" smd circle
			(at 0.40005 0 180)
			(size 0 0)
			(layers "B.Cu" "B.Mask" "B.Paste")
			(net "P3V3_AUX")
		)
		(pad "2" smd circle
			(at -0.40005 0 180)
			(size 0 0)
			(layers "B.Cu" "B.Mask" "B.Paste")
			(net "GND")
		)
	)
	(footprint ""
		(layer "B.Cu")
		(at 39.647114 -61.627766)
		(property "Reference" "R804"
			(at 0 0 0)
			(layer "B.SilkS")
			(hide yes)
			(effects
				(font
					(size 1.27 1.27)
				)
				(justify mirror)
			)
		)
		(property "Value" ""
			(at 0 0 0)
			(layer "B.Fab")
			(effects
				(font
					(size 1.27 1.27)
				)
				(justify mirror)
			)
		)
		(duplicate_pad_numbers_are_jumpers no)
		(fp_line
			(start -0.7874 -0.4064)
			(end -0.7874 0.4064)
			(stroke
				(width 0.1524)
				(type default)
			)
			(layer "B.SilkS")
		)
		(fp_line
			(start -0.7874 0.4064)
			(end 0.7874 0.4064)
			(stroke
				(width 0.1524)
				(type default)
			)
			(layer "B.SilkS")
		)
		(fp_line
			(start 0.7874 -0.4064)
			(end -0.7874 -0.4064)
			(stroke
				(width 0.1524)
				(type default)
			)
			(layer "B.SilkS")
		)
		(fp_line
			(start 0.7874 0.4064)
			(end 0.7874 -0.4064)
			(stroke
				(width 0.1524)
				(type default)
			)
			(layer "B.SilkS")
		)
		(fp_line
			(start -0.67945 -0.3048)
			(end -0.67945 0.3048)
			(stroke
				(width 0.1)
				(type default)
			)
			(layer "B.Fab")
		)
		(fp_line
			(start -0.67945 0.3048)
			(end -0.120396 0.3048)
			(stroke
				(width 0.1)
				(type default)
			)
			(layer "B.Fab")
		)
		(fp_line
			(start -0.12065 -0.3048)
			(end -0.67945 -0.3048)
			(stroke
				(width 0.1)
				(type default)
			)
			(layer "B.Fab")
		)
		(fp_line
			(start -0.12065 -0.2794)
			(end -0.12065 -0.3048)
			(stroke
				(width 0.1)
				(type default)
			)
			(layer "B.Fab")
		)
		(fp_line
			(start -0.120396 0.2794)
			(end 0.12065 0.2794)
			(stroke
				(width 0.1)
				(type default)
			)
			(layer "B.Fab")
		)
		(fp_line
			(start -0.120396 0.3048)
			(end -0.120396 0.2794)
			(stroke
				(width 0.1)
				(type default)
			)
			(layer "B.Fab")
		)
		(fp_line
			(start 0.12065 -0.305054)
			(end 0.12065 -0.2794)
			(stroke
				(width 0.1)
				(type default)
			)
			(layer "B.Fab")
		)
		(fp_line
			(start 0.12065 -0.2794)
			(end -0.12065 -0.2794)
			(stroke
				(width 0.1)
				(type default)
			)
			(layer "B.Fab")
		)
		(fp_line
			(start 0.12065 0.2794)
			(end 0.12065 0.3048)
			(stroke
				(width 0.1)
				(type default)
			)
			(layer "B.Fab")
		)
		(fp_line
			(start 0.12065 0.3048)
			(end 0.67945 0.3048)
			(stroke
				(width 0.1)
				(type default)
			)
			(layer "B.Fab")
		)
		(fp_line
			(start 0.67945 -0.305054)
			(end 0.12065 -0.305054)
			(stroke
				(width 0.1)
				(type default)
			)
			(layer "B.Fab")
		)
		(fp_line
			(start 0.67945 0.3048)
			(end 0.67945 -0.305054)
			(stroke
				(width 0.1)
				(type default)
			)
			(layer "B.Fab")
		)
		(pad "1" smd circle
			(at 0.40005 0 180)
			(size 0 0)
			(layers "B.Cu" "B.Mask" "B.Paste")
			(net "SYS_BMC_PWRBTN_R1_N")
		)
		(pad "2" smd circle
			(at -0.40005 0 180)
			(size 0 0)
			(layers "B.Cu" "B.Mask" "B.Paste")
			(net "SYS_BMC_PWRBTN_R_N")
		)
	)
)
